FILE_TYPE = CONNECTIVITY;
{Allegro Design Entry HDL 16.6-p007 (v16-6-112F) 10/10/2012}
"PAGE_NUMBER" = 56;
0"NC";
1"GND\g";
2"PVCCMCP_CPU1\g";
3"P1V8_MCP_CPU1\g";
4"TP_CPU1_RSVD_288";
5"TP_CPU1_RSVD_219";
6"TP_CPU1_RSVD_211";
7"TP_CPU1_RSVD_223";
8"TP_CPU1_RSVD_298";
9"CPU_XDP_PRESENT_N";
10"TP_CPU1_RSVD_217";
11"TP_CPU1_RSVD_218";
12"H_CPU1_FIVR_FAULT_G";
13"CLK_322M_OSC_CPU1_RC_DP";
14"TP_CPU1_RSVD_TEST_5";
15"TP_CPU1_RSVD_216";
16"TP_CPU1_RSVD_283";
17"TP_CPU1_RSVD_286";
18"TP_CPU1_RSVD_228";
19"VSENSE_P1V8MCP_CPU1_SKT_VRTN";
20"XDP_CPU_PWR_DEBUG_N";
21"TP_CPU1_RSVD_TEST_4";
22"TP_CPU1_RSVD_205";
23"TP_CPU1_RSVD_204";
24"PD_CPU1_RSVD_TEST_2";
25"PD_CPU1_RSVD_TEST_1";
26"TP_CPU1_RSVD_290";
27"TP_CPU1_RSVD_287";
28"TP_CPU1_RSVD_285";
29"TP_CPU1_RSVD_254";
30"TP_CPU1_RSVD_263";
31"TP_CPU1_RSVD_264";
32"TP_CPU1_RSVD_277";
33"TP_CPU1_RSVD_214";
34"PD_CPU1_DMIMODE_OVERRIDE";
35"TP_CPU1_RSVD_208";
36"CLK_100M_CPU1_RC_REFCLK0_DN";
37"TP_CPU1_RSVD_194";
38"TP_CPU1_RSVD_198";
39"CLK_100M_CPU1_RC_REFCLK0_DP";
40"TP_CPU1_RSVD_210";
41"CLK_322M_OSC_CPU1_RC_DN";
42"TP_CPU1_RSVD_TEST_3";
43"VSENSE_P1V8MCP_CPU1_SKT_VSEN";
44"TP_CPU1_RSVD_222";
45"TP_CPU1_RSVD_224";
46"TP_CPU1_RSVD_225";
47"TP_CPU1_RSVD_240";
48"TP_CPU1_RSVD_239";
49"TP_CPU1_RSVD_238";
50"TP_CPU1_RSVD_237";
51"TP_CPU1_RSVD_231";
52"TP_CPU1_RSVD_232";
53"TP_CPU1_RSVD_233";
54"TP_CPU1_RSVD_199";
55"TP_CPU1_RSVD_304";
56"TP_CPU1_RSVD_274";
57"TP_CPU1_RSVD_268";
58"TP_CPU1_RSVD_251";
59"TP_CPU1_RSVD_250";
60"TP_CPU1_RSVD_249";
61"TP_CPU1_RSVD_248";
62"TP_CPU1_RSVD_247";
63"TP_CPU1_RSVD_246";
64"TP_CPU1_RSVD_245";
65"TP_CPU1_RSVD_244";
66"TP_CPU1_RSVD_282";
67"TP_CPU1_RSVD_252";
68"TP_CPU1_RSVD_273";
69"TP_CPU1_RSVD_272";
70"TP_CPU1_RSVD_271";
71"TP_CPU1_RSVD_269";
72"TP_CPU1_RSVD_242";
73"TP_CPU1_RSVD_243";
74"TP_CPU1_RSVD_260";
75"TP_CPU1_RSVD_261";
76"TP_CPU1_RSVD_262";
77"TP_CPU1_RSVD_266";
78"TP_CPU1_RSVD_267";
79"TP_CPU1_RSVD_270";
80"TP_CPU1_RSVD_284";
81"TP_CPU1_RSVD_289";
82"TP_CPU1_RSVD_291";
83"TP_CPU1_RSVD_293";
84"TP_CPU1_RSVD_292";
85"TP_CPU1_RSVD_253";
86"TP_CPU1_RSVD_TEST_11";
87"TP_CPU1_RSVD_259";
88"TP_CPU1_RSVD_258";
89"TP_CPU1_RSVD_256";
90"TP_CPU1_RSVD_265";
91"TP_CPU1_RSVD_281";
92"TP_CPU1_RSVD_280";
93"TP_CPU1_RSVD_279";
94"TP_CPU1_RSVD_278";
95"TP_CPU1_RSVD_276";
96"TP_CPU1_RSVD_275";
97"FM_CPU1_RC_ERROR_N";
98"TP_CPU1_RSVD_303";
99"TP_CPU1_RSVD_299";
100"TP_CPU1_RSVD_300";
101"TP_CPU1_RSVD_212";
102"TP_CPU1_RSVD_226";
103"TP_CPU1_RSVD_227";
104"TP_CPU1_RSVD_229";
105"TP_CPU1_RSVD_230";
106"TP_CPU1_RSVD_234";
107"TP_CPU1_RSVD_235";
108"TP_CPU1_RSVD_236";
109"TP_CPU1_RSVD_241";
%"SKX_EXT_B"
"2","(-4025,2550)","0","chpset_lib","I169";
;
CDS_SEC"2"
LOCATION"U2D1"
PART_NUMBER"TBD"
MATERIAL"IC"
PACK_TYPE"BGA1"
CDS_LIB"chpset_lib"
SEC_TYPE"BGA1"
SEC"2"
CDS_LOCATION"U2D1";
"TEST_5"
$PN"AN14"14;
"TEST_4"
$PN"AN12"21;
"TEST_3"
$PN"AM13"42;
"TEST_2"
$PN"AG46"24;
"TEST_11"
$PN"AY13"86;
"TEST_1"
$PN"AF45"25;
"RSVD<194>"
$PN"AP61"37;
"RSVD<195>"
$PN"AP27"36;
"RSVD<196>"
$PN"AP25"2;
"RSVD<197>"
$PN"AP23"2;
"RSVD<198>"
$PN"AN62"38;
"RSVD<199>"
$PN"AN60"54;
"RSVD<200>"
$PN"AN26"2;
"RSVD<201>"
$PN"AN24"2;
"RSVD<202>"
$PN"AN22"2;
"RSVD<203>"
$PN"AN18"2;
"RSVD<204>"
$PN"AM61"23;
"RSVD<205>"
$PN"AM59"22;
"RSVD<206>"
$PN"AM27"39;
"RSVD<207>"
$PN"AM25"2;
"RSVD<208>"
$PN"AM23"35;
"RSVD<209>"
$PN"AM21"2;
"RSVD<210>"
$PN"AL62"40;
"RSVD<211>"
$PN"AL60"6;
"RSVD<212>"
$PN"AL58"101;
"RSVD<213>"
$PN"AL26"41;
"RSVD<214>"
$PN"AL22"33;
"RSVD<215>"
$PN"AL20"19;
"RSVD<216>"
$PN"AK69"15;
"RSVD<217>"
$PN"AK61"10;
"RSVD<218>"
$PN"AK59"11;
"RSVD<219>"
$PN"AK57"5;
"RSVD<220>"
$PN"AK27"13;
"RSVD<221>"
$PN"AK21"43;
"RSVD<222>"
$PN"AJ70"44;
"RSVD<223>"
$PN"AJ62"7;
"RSVD<224>"
$PN"AJ60"45;
"RSVD<225>"
$PN"AJ58"46;
"RSVD<226>"
$PN"AJ56"102;
"RSVD<227>"
$PN"AJ20"103;
"RSVD<228>"
$PN"AH73"18;
"RSVD<229>"
$PN"AH71"104;
"RSVD<230>"
$PN"AH57"105;
"RSVD<231>"
$PN"AH55"51;
"RSVD<232>"
$PN"AH19"52;
"RSVD<233>"
$PN"AH15"53;
"RSVD<234>"
$PN"AG72"106;
"RSVD<235>"
$PN"AG56"107;
"RSVD<236>"
$PN"AG54"108;
"RSVD<237>"
$PN"AG52"50;
"RSVD<238>"
$PN"AG50"49;
"RSVD<239>"
$PN"AG48"48;
"RSVD<240>"
$PN"AG20"47;
"RSVD<241>"
$PN"AF71"109;
"RSVD<242>"
$PN"AF53"72;
"RSVD<243>"
$PN"AF51"73;
"RSVD<244>"
$PN"AF49"65;
"RSVD<245>"
$PN"AF47"64;
"RSVD<246>"
$PN"AF19"63;
"RSVD<247>"
$PN"AE72"62;
"RSVD<248>"
$PN"AE52"61;
"RSVD<249>"
$PN"AE50"60;
"RSVD<250>"
$PN"AE48"59;
"RSVD<251>"
$PN"AE46"58;
"RSVD<252>"
$PN"AD51"67;
"RSVD<253>"
$PN"AD49"85;
"RSVD<254>"
$PN"AD47"29;
"RSVD<256>"
$PN"Y65"89;
"RSVD<257>"
$PN"Y23"97;
"RSVD<258>"
$PN"W66"88;
"RSVD<259>"
$PN"V67"87;
"RSVD<260>"
$PN"V65"74;
"RSVD<261>"
$PN"U66"75;
"RSVD<262>"
$PN"T67"76;
"RSVD<263>"
$PN"R66"30;
"RSVD<264>"
$PN"R62"31;
"RSVD<265>"
$PN"P65"90;
"RSVD<266>"
$PN"M63"77;
"RSVD<267>"
$PN"K61"78;
"RSVD<268>"
$PN"J62"57;
"RSVD<269>"
$PN"J46"71;
"RSVD<270>"
$PN"H85"79;
"RSVD<271>"
$PN"H83"70;
"RSVD<272>"
$PN"H1"69;
"RSVD<273>"
$PN"G84"68;
"RSVD<274>"
$PN"G64"56;
"RSVD<275>"
$PN"G2"96;
"RSVD<276>"
$PN"F83"95;
"RSVD<277>"
$PN"F65"32;
"RSVD<278>"
$PN"F23"94;
"RSVD<279>"
$PN"F3"93;
"RSVD<280>"
$PN"E84"92;
"RSVD<281>"
$PN"E24"91;
"RSVD<282>"
$PN"E4"66;
"RSVD<283>"
$PN"E2"16;
"RSVD<284>"
$PN"D83"80;
"RSVD<285>"
$PN"D65"28;
"RSVD<286>"
$PN"D17"17;
"RSVD<287>"
$PN"D5"27;
"RSVD<288>"
$PN"C82"4;
"RSVD<289>"
$PN"C24"81;
"RSVD<290>"
$PN"C18"26;
"RSVD<291>"
$PN"C6"82;
"RSVD<292>"
$PN"B81"84;
"RSVD<293>"
$PN"B77"83;
"RSVD<294>"
$PN"B17"3;
"RSVD<295>"
$PN"B15"3;
"RSVD<296>"
$PN"B13"3;
"RSVD<298>"
$PN"B7"8;
"RSVD<299>"
$PN"B3"99;
"RSVD<300>"
$PN"A24"100;
"RSVD<301>"
$PN"A16"3;
"RSVD<302>"
$PN"A14"3;
"RSVD<303>"
$PN"A6"98;
"RSVD<304>"
$PN"A4"55;
"PWR_DEBUG_N"
$PN"AP17"20;
"FIVR_FAULT"
$PN"AU14"12;
"DMIMODE_OVERRIDE"
$PN"AW12"34;
"DEBUG_EN_N"
$PN"AV21"9;
%"GND"
"1","(-375,2425)","0","mstr_symbols","I171";
;
HDL_POWER"GND"
BODY_TYPE"PLUMBING"
CDS_LIB"mstr_symbols"
SIZE"1B"
VOLTAGE"0.0V";
"A\NAC"1;
%"RES"
"2","(-650,2750)","0","mstr_discrete","I173";
;
CDS_SEC"1"
WATTAGE"1/16W"
MATERIAL"CHIP"
PACK_TYPE"0402"
TOLERANCE"1%"
VALUE"49.9"
LOCATION"R8P3"
PART_NUMBER"G21796-047"
ROOM"CPU1"
CDS_LOCATION"R8P3"
SEC"1"
CDS_LIB"mstr_discrete"
SEC_TYPE"0402";
"A"
$PN"1"24;
"B"
$PN"2"1;
%"RES"
"2","(-375,2750)","0","mstr_discrete","I174";
;
CDS_SEC"1"
WATTAGE"1/16W"
MATERIAL"CHIP"
PACK_TYPE"0402"
TOLERANCE"1%"
VALUE"49.9"
PART_NUMBER"G21796-047"
LOCATION"R8R1"
ROOM"CPU1"
CDS_LOCATION"R8R1"
SEC"1"
SEC_TYPE"0402"
CDS_LIB"mstr_discrete";
"A"
$PN"1"25;
"B"
$PN"2"1;
%"VCC_CORE"
"1","(-950,2300)","0","mstr_symbols","I185";
;
HDL_POWER"PVCCMCP_CPU1"
CDS_LIB"mstr_symbols";
"A"2;
%"VCC_CORE"
"1","(-7250,4350)","0","mstr_symbols","I188";
;
HDL_POWER"P1V8_MCP_CPU1"
VOLTAGE"1.8"
CDS_LIB"mstr_symbols";
"A"3;
END.
